# S9S_MB_2U (Grand Teton) — schematic netlist excerpt (pin names and nets, part order shuffled) for the footprints in the layout excerpt that follows; sources: Cadence DE-HDL packaged netlist, KiCad conversion of 03242023_DA0F0TMBIJ0_F0T_Motherboard_J_brd_V01_OCP.brd

C309  Q_CAP  22UF 4V 20% X6S  pkg C0402  page 77 : A = PVCCIN_CPU1 ; B = GND

(kicad_pcb
	(version 20260206)
	(generator "pcbnew")
	(generator_version "10.0")
	(general
		(thickness 1.6)
		(legacy_teardrops no)
	)
	(paper "A4")
	(title_block
		(title "03242023_DA0F0TMBIJ0_F0T_Motherboard_J_brd_V01_OCP.brd")
		(comment 1 "Grand Teton / footprints 3512-3512 of 6105")
	)
	(layers
		(0 "F.Cu" signal "TOP")
		(4 "In1.Cu" signal "GND")
		(6 "In2.Cu" signal "IN1")
		(8 "In3.Cu" signal "GND1")
		(10 "In4.Cu" signal "IN2")
		(12 "In5.Cu" signal "GND2")
		(14 "In6.Cu" signal "IN3")
		(16 "In7.Cu" signal "GND3")
		(18 "In8.Cu" signal "VCC")
		(20 "In9.Cu" signal "VCC1")
		(22 "In10.Cu" signal "GND4")
		(24 "In11.Cu" signal "IN4")
		(26 "In12.Cu" signal "GND5")
		(28 "In13.Cu" signal "IN5")
		(30 "In14.Cu" signal "GND6")
		(32 "In15.Cu" signal "IN6")
		(34 "In16.Cu" signal "GND7")
		(2 "B.Cu" signal "BOTTOM")
		(9 "F.Adhes" user "F.Adhesive")
		(11 "B.Adhes" user "B.Adhesive")
		(13 "F.Paste" user "Package Geometry/Pastemask Top")
		(15 "B.Paste" user "Package Geometry/Pastemask Bottom")
		(5 "F.SilkS" user "Ref Des/Silkscreen Top")
		(7 "B.SilkS" user "Ref Des/Silkscreen Bottom")
		(1 "F.Mask" user "Board Geometry/Soldermask Top")
		(3 "B.Mask" user "Board Geometry/Soldermask Bottom")
		(17 "Dwgs.User" user "User.Drawings")
		(19 "Cmts.User" user "User.Comments")
		(21 "Eco1.User" user "User.Eco1")
		(23 "Eco2.User" user "User.Eco2")
		(25 "Edge.Cuts" user "Board Geometry/Outline")
		(27 "Margin" user)
		(31 "F.CrtYd" user "Package Geometry/Place Bound Top")
		(29 "B.CrtYd" user "Package Geometry/Place Bound Bottom")
		(35 "F.Fab" user "Ref Des/Assembly Top")
		(33 "B.Fab" user "Ref Des/Assembly Bottom")
	)
	(footprint ""
		(layer "F.Cu")
		(at 116.561616 -249.320558 -90)
		(property "Reference" "C309"
			(at 0 0 270)
			(layer "F.SilkS")
			(hide yes)
			(effects
				(font
					(size 1.27 1.27)
				)
			)
		)
		(property "Value" ""
			(at 0 0 270)
			(layer "F.Fab")
			(effects
				(font
					(size 1.27 1.27)
				)
			)
		)
		(duplicate_pad_numbers_are_jumpers no)
		(fp_line
			(start -0.7874 0.4064)
			(end -0.7874 -0.4064)
			(stroke
				(width 0.1524)
				(type default)
			)
			(layer "F.SilkS")
		)
		(fp_line
			(start 0.7874 0.4064)
			(end -0.7874 0.4064)
			(stroke
				(width 0.1524)
				(type default)
			)
			(layer "F.SilkS")
		)
		(fp_line
			(start -0.7874 -0.4064)
			(end 0.7874 -0.4064)
			(stroke
				(width 0.1524)
				(type default)
			)
			(layer "F.SilkS")
		)
		(fp_line
			(start 0.7874 -0.4064)
			(end 0.7874 0.4064)
			(stroke
				(width 0.1524)
				(type default)
			)
			(layer "F.SilkS")
		)
		(fp_line
			(start -0.67945 0.3048)
			(end -0.67945 -0.305054)
			(stroke
				(width 0.1)
				(type default)
			)
			(layer "F.Fab")
		)
		(fp_line
			(start -0.12065 0.3048)
			(end -0.67945 0.3048)
			(stroke
				(width 0.1)
				(type default)
			)
			(layer "F.Fab")
		)
		(fp_line
			(start 0.120396 0.3048)
			(end 0.120396 0.2794)
			(stroke
				(width 0.1)
				(type default)
			)
			(layer "F.Fab")
		)
		(fp_line
			(start 0.67945 0.3048)
			(end 0.120396 0.3048)
			(stroke
				(width 0.1)
				(type default)
			)
			(layer "F.Fab")
		)
		(fp_line
			(start -0.12065 0.2794)
			(end -0.12065 0.3048)
			(stroke
				(width 0.1)
				(type default)
			)
			(layer "F.Fab")
		)
		(fp_line
			(start 0.120396 0.2794)
			(end -0.12065 0.2794)
			(stroke
				(width 0.1)
				(type default)
			)
			(layer "F.Fab")
		)
		(fp_line
			(start -0.12065 -0.2794)
			(end 0.12065 -0.2794)
			(stroke
				(width 0.1)
				(type default)
			)
			(layer "F.Fab")
		)
		(fp_line
			(start 0.12065 -0.2794)
			(end 0.12065 -0.3048)
			(stroke
				(width 0.1)
				(type default)
			)
			(layer "F.Fab")
		)
		(fp_line
			(start 0.12065 -0.3048)
			(end 0.67945 -0.3048)
			(stroke
				(width 0.1)
				(type default)
			)
			(layer "F.Fab")
		)
		(fp_line
			(start 0.67945 -0.3048)
			(end 0.67945 0.3048)
			(stroke
				(width 0.1)
				(type default)
			)
			(layer "F.Fab")
		)
		(fp_line
			(start -0.67945 -0.305054)
			(end -0.12065 -0.305054)
			(stroke
				(width 0.1)
				(type default)
			)
			(layer "F.Fab")
		)
		(fp_line
			(start -0.12065 -0.305054)
			(end -0.12065 -0.2794)
			(stroke
				(width 0.1)
				(type default)
			)
			(layer "F.Fab")
		)
		(pad "1" smd circle
			(at -0.40005 0 270)
			(size 0 0)
			(layers "F.Cu" "F.Mask" "F.Paste")
			(net "PVCCIN_CPU1")
		)
		(pad "2" smd circle
			(at 0.40005 0 270)
			(size 0 0)
			(layers "F.Cu" "F.Mask" "F.Paste")
			(net "GND")
		)
	)
)
